# S9S_MB_2U (Grand Teton) — schematic netlist excerpt (pin names and nets, part order shuffled) for the footprints in the layout excerpt that follows; sources: Cadence DE-HDL packaged netlist, KiCad conversion of 03242023_DA0F0TMBIJ0_F0T_Motherboard_J_brd_V01_OCP.brd

PR3782  Q_RES  10 1% CHIP  pkg 0402LF  page 162 : A = P3V3_AUX ; B = P3V3_OCP_VCC_2
PC577  Q_CAP  0.1UF 25V 10% X7R  pkg 0402  page 259 : A = SW_P3V3_AUX_FLT ; B = GND

(kicad_pcb
	(version 20260206)
	(generator "pcbnew")
	(generator_version "10.0")
	(general
		(thickness 1.6)
		(legacy_teardrops no)
	)
	(paper "A4")
	(title_block
		(title "03242023_DA0F0TMBIJ0_F0T_Motherboard_J_brd_V01_OCP.brd")
		(comment 1 "Grand Teton / footprints 3181-3182 of 6105")
	)
	(layers
		(0 "F.Cu" signal "TOP")
		(4 "In1.Cu" signal "GND")
		(6 "In2.Cu" signal "IN1")
		(8 "In3.Cu" signal "GND1")
		(10 "In4.Cu" signal "IN2")
		(12 "In5.Cu" signal "GND2")
		(14 "In6.Cu" signal "IN3")
		(16 "In7.Cu" signal "GND3")
		(18 "In8.Cu" signal "VCC")
		(20 "In9.Cu" signal "VCC1")
		(22 "In10.Cu" signal "GND4")
		(24 "In11.Cu" signal "IN4")
		(26 "In12.Cu" signal "GND5")
		(28 "In13.Cu" signal "IN5")
		(30 "In14.Cu" signal "GND6")
		(32 "In15.Cu" signal "IN6")
		(34 "In16.Cu" signal "GND7")
		(2 "B.Cu" signal "BOTTOM")
		(9 "F.Adhes" user "F.Adhesive")
		(11 "B.Adhes" user "B.Adhesive")
		(13 "F.Paste" user "Package Geometry/Pastemask Top")
		(15 "B.Paste" user "Package Geometry/Pastemask Bottom")
		(5 "F.SilkS" user "Ref Des/Silkscreen Top")
		(7 "B.SilkS" user "Ref Des/Silkscreen Bottom")
		(1 "F.Mask" user "Board Geometry/Soldermask Top")
		(3 "B.Mask" user "Board Geometry/Soldermask Bottom")
		(17 "Dwgs.User" user "User.Drawings")
		(19 "Cmts.User" user "User.Comments")
		(21 "Eco1.User" user "User.Eco1")
		(23 "Eco2.User" user "User.Eco2")
		(25 "Edge.Cuts" user "Board Geometry/Outline")
		(27 "Margin" user)
		(31 "F.CrtYd" user "Package Geometry/Place Bound Top")
		(29 "B.CrtYd" user "Package Geometry/Place Bound Bottom")
		(35 "F.Fab" user "Ref Des/Assembly Top")
		(33 "B.Fab" user "Ref Des/Assembly Bottom")
	)
	(footprint ""
		(layer "F.Cu")
		(at 451.923404 -71.019416 -90)
		(property "Reference" "PC577"
			(at 0 0 270)
			(layer "F.SilkS")
			(hide yes)
			(effects
				(font
					(size 1.27 1.27)
				)
			)
		)
		(property "Value" ""
			(at 0 0 270)
			(layer "F.Fab")
			(effects
				(font
					(size 1.27 1.27)
				)
			)
		)
		(duplicate_pad_numbers_are_jumpers no)
		(fp_line
			(start -0.7874 0.4064)
			(end -0.7874 -0.4064)
			(stroke
				(width 0.1524)
				(type default)
			)
			(layer "F.SilkS")
		)
		(fp_line
			(start 0.7874 0.4064)
			(end -0.7874 0.4064)
			(stroke
				(width 0.1524)
				(type default)
			)
			(layer "F.SilkS")
		)
		(fp_line
			(start -0.7874 -0.4064)
			(end 0.7874 -0.4064)
			(stroke
				(width 0.1524)
				(type default)
			)
			(layer "F.SilkS")
		)
		(fp_line
			(start 0.7874 -0.4064)
			(end 0.7874 0.4064)
			(stroke
				(width 0.1524)
				(type default)
			)
			(layer "F.SilkS")
		)
		(fp_line
			(start -0.67945 0.3048)
			(end -0.67945 -0.305054)
			(stroke
				(width 0.1)
				(type default)
			)
			(layer "F.Fab")
		)
		(fp_line
			(start -0.12065 0.3048)
			(end -0.67945 0.3048)
			(stroke
				(width 0.1)
				(type default)
			)
			(layer "F.Fab")
		)
		(fp_line
			(start 0.120396 0.3048)
			(end 0.120396 0.2794)
			(stroke
				(width 0.1)
				(type default)
			)
			(layer "F.Fab")
		)
		(fp_line
			(start 0.67945 0.3048)
			(end 0.120396 0.3048)
			(stroke
				(width 0.1)
				(type default)
			)
			(layer "F.Fab")
		)
		(fp_line
			(start -0.12065 0.2794)
			(end -0.12065 0.3048)
			(stroke
				(width 0.1)
				(type default)
			)
			(layer "F.Fab")
		)
		(fp_line
			(start 0.120396 0.2794)
			(end -0.12065 0.2794)
			(stroke
				(width 0.1)
				(type default)
			)
			(layer "F.Fab")
		)
		(fp_line
			(start -0.12065 -0.2794)
			(end 0.12065 -0.2794)
			(stroke
				(width 0.1)
				(type default)
			)
			(layer "F.Fab")
		)
		(fp_line
			(start 0.12065 -0.2794)
			(end 0.12065 -0.3048)
			(stroke
				(width 0.1)
				(type default)
			)
			(layer "F.Fab")
		)
		(fp_line
			(start 0.12065 -0.3048)
			(end 0.67945 -0.3048)
			(stroke
				(width 0.1)
				(type default)
			)
			(layer "F.Fab")
		)
		(fp_line
			(start 0.67945 -0.3048)
			(end 0.67945 0.3048)
			(stroke
				(width 0.1)
				(type default)
			)
			(layer "F.Fab")
		)
		(fp_line
			(start -0.67945 -0.305054)
			(end -0.12065 -0.305054)
			(stroke
				(width 0.1)
				(type default)
			)
			(layer "F.Fab")
		)
		(fp_line
			(start -0.12065 -0.305054)
			(end -0.12065 -0.2794)
			(stroke
				(width 0.1)
				(type default)
			)
			(layer "F.Fab")
		)
		(pad "1" smd circle
			(at -0.40005 0 270)
			(size 0 0)
			(layers "F.Cu" "F.Mask" "F.Paste")
			(net "SW_P3V3_AUX_FLT")
		)
		(pad "2" smd circle
			(at 0.40005 0 270)
			(size 0 0)
			(layers "F.Cu" "F.Mask" "F.Paste")
			(net "GND")
		)
	)
	(footprint ""
		(layer "F.Cu")
		(at 86.931246 -57.279286 90)
		(property "Reference" "PR3782"
			(at 0 0 90)
			(layer "F.SilkS")
			(hide yes)
			(effects
				(font
					(size 1.27 1.27)
				)
			)
		)
		(property "Value" ""
			(at 0 0 90)
			(layer "F.Fab")
			(effects
				(font
					(size 1.27 1.27)
				)
			)
		)
		(duplicate_pad_numbers_are_jumpers no)
		(fp_line
			(start 0.7874 -0.4064)
			(end 0.7874 0.4064)
			(stroke
				(width 0.1524)
				(type default)
			)
			(layer "F.SilkS")
		)
		(fp_line
			(start -0.7874 -0.4064)
			(end 0.7874 -0.4064)
			(stroke
				(width 0.1524)
				(type default)
			)
			(layer "F.SilkS")
		)
		(fp_line
			(start 0.7874 0.4064)
			(end -0.7874 0.4064)
			(stroke
				(width 0.1524)
				(type default)
			)
			(layer "F.SilkS")
		)
		(fp_line
			(start -0.7874 0.4064)
			(end -0.7874 -0.4064)
			(stroke
				(width 0.1524)
				(type default)
			)
			(layer "F.SilkS")
		)
		(fp_line
			(start -0.12065 -0.305054)
			(end -0.12065 -0.2794)
			(stroke
				(width 0.1)
				(type default)
			)
			(layer "F.Fab")
		)
		(fp_line
			(start -0.67945 -0.305054)
			(end -0.12065 -0.305054)
			(stroke
				(width 0.1)
				(type default)
			)
			(layer "F.Fab")
		)
		(fp_line
			(start 0.67945 -0.3048)
			(end 0.67945 0.3048)
			(stroke
				(width 0.1)
				(type default)
			)
			(layer "F.Fab")
		)
		(fp_line
			(start 0.12065 -0.3048)
			(end 0.67945 -0.3048)
			(stroke
				(width 0.1)
				(type default)
			)
			(layer "F.Fab")
		)
		(fp_line
			(start 0.12065 -0.2794)
			(end 0.12065 -0.3048)
			(stroke
				(width 0.1)
				(type default)
			)
			(layer "F.Fab")
		)
		(fp_line
			(start -0.12065 -0.2794)
			(end 0.12065 -0.2794)
			(stroke
				(width 0.1)
				(type default)
			)
			(layer "F.Fab")
		)
		(fp_line
			(start 0.120396 0.2794)
			(end -0.12065 0.2794)
			(stroke
				(width 0.1)
				(type default)
			)
			(layer "F.Fab")
		)
		(fp_line
			(start -0.12065 0.2794)
			(end -0.12065 0.3048)
			(stroke
				(width 0.1)
				(type default)
			)
			(layer "F.Fab")
		)
		(fp_line
			(start 0.67945 0.3048)
			(end 0.120396 0.3048)
			(stroke
				(width 0.1)
				(type default)
			)
			(layer "F.Fab")
		)
		(fp_line
			(start 0.120396 0.3048)
			(end 0.120396 0.2794)
			(stroke
				(width 0.1)
				(type default)
			)
			(layer "F.Fab")
		)
		(fp_line
			(start -0.12065 0.3048)
			(end -0.67945 0.3048)
			(stroke
				(width 0.1)
				(type default)
			)
			(layer "F.Fab")
		)
		(fp_line
			(start -0.67945 0.3048)
			(end -0.67945 -0.305054)
			(stroke
				(width 0.1)
				(type default)
			)
			(layer "F.Fab")
		)
		(pad "1" smd circle
			(at -0.40005 0 90)
			(size 0 0)
			(layers "F.Cu" "F.Mask" "F.Paste")
			(net "P3V3_AUX")
		)
		(pad "2" smd circle
			(at 0.40005 0 90)
			(size 0 0)
			(layers "F.Cu" "F.Mask" "F.Paste")
			(net "P3V3_OCP_VCC_2")
		)
	)
)
